(kicad_pcb
	(version 20260206)
	(generator "pcbnew")
	(generator_version "10.0")
	(general
		(thickness 1.6)
		(legacy_teardrops no)
	)
	(paper "A4")
	(title_block
		(title "peb — Lightning_PEB_BRD.brd")
		(comment 1 "Lightning (Wiwynn / Facebook NVMe JBOF) / footprints 2427-2435 of 2563")
	)
	(layers
		(0 "F.Cu" signal "TOP")
		(4 "In1.Cu" signal "L2GND")
		(6 "In2.Cu" signal "L3")
		(8 "In3.Cu" signal "L4VCC")
		(10 "In4.Cu" signal "L5VCC")
		(12 "In5.Cu" signal "L6")
		(14 "In6.Cu" signal "L7GND")
		(2 "B.Cu" signal "BOTTOM")
		(9 "F.Adhes" user "F.Adhesive")
		(11 "B.Adhes" user "B.Adhesive")
		(13 "F.Paste" user "Package Geometry/Pastemask Top")
		(15 "B.Paste" user "Package Geometry/Pastemask Bottom")
		(5 "F.SilkS" user "Ref Des/Silkscreen Top")
		(7 "B.SilkS" user "Ref Des/Silkscreen Bottom")
		(1 "F.Mask" user "Board Geometry/Soldermask Top")
		(3 "B.Mask" user "Board Geometry/Soldermask Bottom")
		(17 "Dwgs.User" user "User.Drawings")
		(19 "Cmts.User" user "User.Comments")
		(21 "Eco1.User" user "User.Eco1")
		(23 "Eco2.User" user "User.Eco2")
		(25 "Edge.Cuts" user "Board Geometry/Outline")
		(27 "Margin" user)
		(31 "F.CrtYd" user "Package Geometry/Place Bound Top")
		(29 "B.CrtYd" user "Package Geometry/Place Bound Bottom")
		(35 "F.Fab" user "Ref Des/Assembly Top")
		(33 "B.Fab" user "Ref Des/Assembly Bottom")
	)
	(footprint ""
		(layer "B.Cu")
		(at 231.60228 -40.005 90)
		(property "Reference" "TP214"
			(at 0 0 90)
			(layer "B.SilkS")
			(hide yes)
			(effects
				(font
					(size 1.27 1.27)
				)
				(justify mirror)
			)
		)
		(property "Value" "TPAD28-2-GP"
			(at 0.0127 -1.6637 90)
			(unlocked yes)
			(layer "B.Fab")
			(hide yes)
			(effects
				(font
					(size 1.016 1.016)
					(thickness 0.1524)
				)
				(justify mirror)
			)
		)
		(property "Device Type" "TPAD28"
			(at 0.0127 -3.1877 90)
			(unlocked yes)
			(layer "B.Fab")
			(hide yes)
			(effects
				(font
					(size 1.016 1.016)
					(thickness 0.1524)
				)
				(justify mirror)
			)
		)
		(duplicate_pad_numbers_are_jumpers no)
		(fp_poly
			(pts
				(arc
					(start 0 0.3556)
					(mid 0 -0.3556)
					(end 0 0.3556)
				)
			)
			(stroke
				(width 0)
				(type default)
			)
			(fill no)
			(layer "B.CrtYd")
		)
		(fp_poly
			(pts
				(arc
					(start 0 0.6096)
					(mid 0 -0.6096)
					(end 0 0.6096)
				)
			)
			(stroke
				(width 0)
				(type default)
			)
			(fill no)
			(layer "B.Fab")
		)
		(pad "1" smd circle
			(at 0 0 270)
			(size 0.7112 0.7112)
			(layers "B.Cu" "B.Mask" "B.Paste")
			(net "LINK")
		)
	)
	(footprint ""
		(layer "B.Cu")
		(at 50.673 -181.483 180)
		(property "Reference" "R902"
			(at 0 0 0)
			(layer "B.SilkS")
			(hide yes)
			(effects
				(font
					(size 1.27 1.27)
				)
				(justify mirror)
			)
		)
		(property "Value" "0R2J-2-GP"
			(at -0.064008 -3.993896 180)
			(unlocked yes)
			(layer "B.Fab")
			(hide yes)
			(effects
				(font
					(size 1.016 1.016)
					(thickness 0.1524)
				)
				(justify mirror)
			)
		)
		(property "Device Type" "R402H16"
			(at -0.064008 -5.517896 180)
			(unlocked yes)
			(layer "B.Fab")
			(hide yes)
			(effects
				(font
					(size 1.016 1.016)
					(thickness 0.1524)
				)
				(justify mirror)
			)
		)
		(duplicate_pad_numbers_are_jumpers no)
		(fp_line
			(start 0.508 -0.9398)
			(end 0.508 0.9398)
			(stroke
				(width 0.1524)
				(type default)
			)
			(layer "B.SilkS")
		)
		(fp_line
			(start -0.508 -0.9398)
			(end 0.508 -0.9398)
			(stroke
				(width 0.1524)
				(type default)
			)
			(layer "B.SilkS")
		)
		(fp_rect
			(start 0.508 0.9398)
			(end -0.508 -0.9398)
			(stroke
				(width 0)
				(type default)
			)
			(fill no)
			(layer "B.CrtYd")
		)
		(fp_rect
			(start 0.508 0.9398)
			(end -0.508 -0.9398)
			(stroke
				(width 0)
				(type default)
			)
			(fill no)
			(layer "B.Fab")
		)
		(pad "1" smd custom
			(at 0 -0.4445)
			(size 0.1397 0.1397)
			(layers "B.Cu" "B.Mask" "B.Paste")
			(net "BMC_I2C8_CLKBUF1_SDA")
			(options
				(clearance outline)
				(anchor circle)
			)
			(primitives
				(gr_poly
					(pts
						(arc
							(start -0.1778 0.2794)
							(mid -0.249642 0.249642)
							(end -0.2794 0.1778)
						)
						(arc
							(start -0.2794 -0.1778)
							(mid -0.249642 -0.249642)
							(end -0.1778 -0.2794)
						)
						(arc
							(start 0.1778 -0.2794)
							(mid 0.249642 -0.249642)
							(end 0.2794 -0.1778)
						)
						(arc
							(start 0.2794 0.1778)
							(mid 0.249642 0.249642)
							(end 0.1778 0.2794)
						)
					)
					(width 0)
					(fill yes)
				)
			)
		)
		(pad "2" smd custom
			(at 0 0.4445)
			(size 0.1397 0.1397)
			(layers "B.Cu" "B.Mask" "B.Paste")
			(net "BUF_I2C8_CLKBUF1_SDA")
			(options
				(clearance outline)
				(anchor circle)
			)
			(primitives
				(gr_poly
					(pts
						(arc
							(start -0.1778 0.2794)
							(mid -0.249642 0.249642)
							(end -0.2794 0.1778)
						)
						(arc
							(start -0.2794 -0.1778)
							(mid -0.249642 -0.249642)
							(end -0.1778 -0.2794)
						)
						(arc
							(start 0.1778 -0.2794)
							(mid 0.249642 -0.249642)
							(end 0.2794 -0.1778)
						)
						(arc
							(start 0.2794 0.1778)
							(mid 0.249642 0.249642)
							(end 0.1778 0.2794)
						)
					)
					(width 0)
					(fill yes)
				)
			)
		)
	)
	(footprint ""
		(layer "B.Cu")
		(at 219.59824 -200.37552 -90)
		(property "Reference" "R3210"
			(at 0 0 90)
			(layer "B.SilkS")
			(hide yes)
			(effects
				(font
					(size 1.27 1.27)
				)
				(justify mirror)
			)
		)
		(property "Value" "0R2J-2-GP"
			(at -0.064008 -3.993896 270)
			(unlocked yes)
			(layer "B.Fab")
			(hide yes)
			(effects
				(font
					(size 1.016 1.016)
					(thickness 0.1524)
				)
				(justify mirror)
			)
		)
		(property "Device Type" "R402H16"
			(at -0.064008 -5.517896 270)
			(unlocked yes)
			(layer "B.Fab")
			(hide yes)
			(effects
				(font
					(size 1.016 1.016)
					(thickness 0.1524)
				)
				(justify mirror)
			)
		)
		(duplicate_pad_numbers_are_jumpers no)
		(fp_line
			(start -0.508 -0.9398)
			(end 0.508 -0.9398)
			(stroke
				(width 0.1524)
				(type default)
			)
			(layer "B.SilkS")
		)
		(fp_line
			(start 0.508 -0.9398)
			(end 0.508 0.9398)
			(stroke
				(width 0.1524)
				(type default)
			)
			(layer "B.SilkS")
		)
		(fp_rect
			(start 0.508 0.9398)
			(end -0.508 -0.9398)
			(stroke
				(width 0)
				(type default)
			)
			(fill no)
			(layer "B.CrtYd")
		)
		(fp_rect
			(start 0.508 0.9398)
			(end -0.508 -0.9398)
			(stroke
				(width 0)
				(type default)
			)
			(fill no)
			(layer "B.Fab")
		)
		(pad "1" smd custom
			(at 0 -0.4445 90)
			(size 0.1397 0.1397)
			(layers "B.Cu" "B.Mask" "B.Paste")
			(net "SSD_PERST#3")
			(options
				(clearance outline)
				(anchor circle)
			)
			(primitives
				(gr_poly
					(pts
						(arc
							(start -0.1778 0.2794)
							(mid -0.249642 0.249642)
							(end -0.2794 0.1778)
						)
						(arc
							(start -0.2794 -0.1778)
							(mid -0.249642 -0.249642)
							(end -0.1778 -0.2794)
						)
						(arc
							(start 0.1778 -0.2794)
							(mid 0.249642 -0.249642)
							(end 0.2794 -0.1778)
						)
						(arc
							(start 0.2794 0.1778)
							(mid 0.249642 0.249642)
							(end 0.1778 0.2794)
						)
					)
					(width 0)
					(fill yes)
				)
			)
		)
		(pad "2" smd custom
			(at 0 0.4445 90)
			(size 0.1397 0.1397)
			(layers "B.Cu" "B.Mask" "B.Paste")
			(net "SSD_PERST#0_B3")
			(options
				(clearance outline)
				(anchor circle)
			)
			(primitives
				(gr_poly
					(pts
						(arc
							(start -0.1778 0.2794)
							(mid -0.249642 0.249642)
							(end -0.2794 0.1778)
						)
						(arc
							(start -0.2794 -0.1778)
							(mid -0.249642 -0.249642)
							(end -0.1778 -0.2794)
						)
						(arc
							(start 0.1778 -0.2794)
							(mid 0.249642 -0.249642)
							(end 0.2794 -0.1778)
						)
						(arc
							(start 0.2794 0.1778)
							(mid 0.249642 0.249642)
							(end 0.1778 0.2794)
						)
					)
					(width 0)
					(fill yes)
				)
			)
		)
	)
	(footprint ""
		(layer "B.Cu")
		(at 57.15 -133.985 180)
		(property "Reference" "R5771"
			(at 0 0 0)
			(layer "B.SilkS")
			(hide yes)
			(effects
				(font
					(size 1.27 1.27)
				)
				(justify mirror)
			)
		)
		(property "Value" "1KR2F-3-GP"
			(at -0.064008 -3.993896 180)
			(unlocked yes)
			(layer "B.Fab")
			(hide yes)
			(effects
				(font
					(size 1.016 1.016)
					(thickness 0.1524)
				)
				(justify mirror)
			)
		)
		(property "Device Type" "R402H16"
			(at -0.064008 -5.517896 180)
			(unlocked yes)
			(layer "B.Fab")
			(hide yes)
			(effects
				(font
					(size 1.016 1.016)
					(thickness 0.1524)
				)
				(justify mirror)
			)
		)
		(duplicate_pad_numbers_are_jumpers no)
		(fp_line
			(start 0.508 -0.9398)
			(end 0.508 0.9398)
			(stroke
				(width 0.1524)
				(type default)
			)
			(layer "B.SilkS")
		)
		(fp_line
			(start -0.508 -0.9398)
			(end 0.508 -0.9398)
			(stroke
				(width 0.1524)
				(type default)
			)
			(layer "B.SilkS")
		)
		(fp_rect
			(start 0.508 0.9398)
			(end -0.508 -0.9398)
			(stroke
				(width 0)
				(type default)
			)
			(fill no)
			(layer "B.CrtYd")
		)
		(fp_rect
			(start 0.508 0.9398)
			(end -0.508 -0.9398)
			(stroke
				(width 0)
				(type default)
			)
			(fill no)
			(layer "B.Fab")
		)
		(pad "1" smd custom
			(at 0 -0.4445)
			(size 0.1397 0.1397)
			(layers "B.Cu" "B.Mask" "B.Paste")
			(net "ADC_P5V_STBY")
			(options
				(clearance outline)
				(anchor circle)
			)
			(primitives
				(gr_poly
					(pts
						(arc
							(start -0.1778 0.2794)
							(mid -0.249642 0.249642)
							(end -0.2794 0.1778)
						)
						(arc
							(start -0.2794 -0.1778)
							(mid -0.249642 -0.249642)
							(end -0.1778 -0.2794)
						)
						(arc
							(start 0.1778 -0.2794)
							(mid 0.249642 -0.249642)
							(end 0.2794 -0.1778)
						)
						(arc
							(start 0.2794 0.1778)
							(mid 0.249642 0.249642)
							(end 0.1778 0.2794)
						)
					)
					(width 0)
					(fill yes)
				)
			)
		)
		(pad "2" smd custom
			(at 0 0.4445)
			(size 0.1397 0.1397)
			(layers "B.Cu" "B.Mask" "B.Paste")
			(net "GND")
			(options
				(clearance outline)
				(anchor circle)
			)
			(primitives
				(gr_poly
					(pts
						(arc
							(start -0.1778 0.2794)
							(mid -0.249642 0.249642)
							(end -0.2794 0.1778)
						)
						(arc
							(start -0.2794 -0.1778)
							(mid -0.249642 -0.249642)
							(end -0.1778 -0.2794)
						)
						(arc
							(start 0.1778 -0.2794)
							(mid 0.249642 -0.249642)
							(end 0.2794 -0.1778)
						)
						(arc
							(start 0.2794 0.1778)
							(mid 0.249642 0.249642)
							(end 0.1778 0.2794)
						)
					)
					(width 0)
					(fill yes)
				)
			)
		)
	)
	(footprint ""
		(layer "B.Cu")
		(at 176.723802 -71.071232 90)
		(property "Reference" "PG35"
			(at 0 0 90)
			(layer "B.SilkS")
			(hide yes)
			(effects
				(font
					(size 1.27 1.27)
				)
				(justify mirror)
			)
		)
		(property "Value" "GAP-CLOSE-PWR-3-GP"
			(at -0.0254 -6.5786 90)
			(unlocked yes)
			(layer "B.Fab")
			(hide yes)
			(effects
				(font
					(size 1.016 1.016)
					(thickness 0.1524)
				)
				(justify mirror)
			)
		)
		(property "Device Type" "GAP-CLOSE-PWR-3"
			(at -0.0254 -8.255 90)
			(unlocked yes)
			(layer "B.Fab")
			(hide yes)
			(effects
				(font
					(size 1.016 1.016)
					(thickness 0.1524)
				)
				(justify mirror)
			)
		)
		(duplicate_pad_numbers_are_jumpers no)
		(fp_rect
			(start 0.7112 0.4572)
			(end -0.7112 -0.4572)
			(stroke
				(width 0)
				(type default)
			)
			(fill no)
			(layer "B.CrtYd")
		)
		(fp_poly
			(pts
				(xy 0.7112 -0.4572) (xy -0.7112 -0.4572) (xy -0.7112 0.4572) (xy 0.7112 0.4572)
			)
			(stroke
				(width 0)
				(type default)
			)
			(fill no)
			(layer "B.Fab")
		)
		(pad "1" smd rect
			(at 0.3048 0 270)
			(size 0.6604 0.762)
			(layers "B.Cu" "B.Mask" "B.Paste")
			(net "DUT_AVD_TX")
		)
		(pad "2" smd rect
			(at -0.3048 0 270)
			(size 0.6604 0.762)
			(layers "B.Cu" "B.Mask" "B.Paste")
			(net "P0V9")
		)
	)
	(footprint ""
		(layer "B.Cu")
		(at 245.599966 -37.999924)
		(property "Reference" "TP310"
			(at 0 0 0)
			(layer "B.SilkS")
			(hide yes)
			(effects
				(font
					(size 1.27 1.27)
				)
				(justify mirror)
			)
		)
		(property "Value" "TPAD28-2-GP"
			(at 0.0127 -1.6637 0)
			(unlocked yes)
			(layer "B.Fab")
			(hide yes)
			(effects
				(font
					(size 1.016 1.016)
					(thickness 0.1524)
				)
				(justify mirror)
			)
		)
		(property "Device Type" "TPAD28"
			(at 0.0127 -3.1877 0)
			(unlocked yes)
			(layer "B.Fab")
			(hide yes)
			(effects
				(font
					(size 1.016 1.016)
					(thickness 0.1524)
				)
				(justify mirror)
			)
		)
		(duplicate_pad_numbers_are_jumpers no)
		(fp_poly
			(pts
				(arc
					(start 0.3556 0)
					(mid -0.3556 0)
					(end 0.3556 0)
				)
			)
			(stroke
				(width 0)
				(type default)
			)
			(fill no)
			(layer "B.CrtYd")
		)
		(fp_poly
			(pts
				(arc
					(start 0.6096 0)
					(mid -0.6096 0)
					(end 0.6096 0)
				)
			)
			(stroke
				(width 0)
				(type default)
			)
			(fill no)
			(layer "B.Fab")
		)
		(pad "1" smd circle
			(at 0 0 180)
			(size 0.7112 0.7112)
			(layers "B.Cu" "B.Mask" "B.Paste")
			(net "TPIN")
		)
	)
	(footprint ""
		(layer "B.Cu")
		(at 241.0968 -51.9938 90)
		(property "Reference" "C460"
			(at 0 0 90)
			(layer "B.SilkS")
			(hide yes)
			(effects
				(font
					(size 1.27 1.27)
				)
				(justify mirror)
			)
		)
		(property "Value" "SCD1U16V1KX-1-GP"
			(at 2.8321 -1.7399 90)
			(unlocked yes)
			(layer "B.Fab")
			(hide yes)
			(effects
				(font
					(size 1.016 1.016)
					(thickness 0.1524)
				)
				(justify mirror)
			)
		)
		(property "Device Type" "C0201H13"
			(at 2.8321 -3.2639 90)
			(unlocked yes)
			(layer "B.Fab")
			(hide yes)
			(effects
				(font
					(size 1.016 1.016)
					(thickness 0.1524)
				)
				(justify mirror)
			)
		)
		(duplicate_pad_numbers_are_jumpers no)
		(fp_rect
			(start 0.2794 0.6477)
			(end -0.2794 -0.6477)
			(stroke
				(width 0)
				(type default)
			)
			(fill no)
			(layer "B.CrtYd")
		)
		(fp_rect
			(start 0.2794 0.6477)
			(end -0.2794 -0.6477)
			(stroke
				(width 0)
				(type default)
			)
			(fill no)
			(layer "B.Fab")
		)
		(pad "1" smd custom
			(at 0 -0.2794 270)
			(size 0.0762 0.0762)
			(layers "B.Cu" "B.Mask" "B.Paste")
			(net "DUT_VDD")
			(options
				(clearance outline)
				(anchor circle)
			)
			(primitives
				(gr_poly
					(pts
						(arc
							(start 0.1524 0.127)
							(mid 0.137521 0.162921)
							(end 0.1016 0.1778)
						)
						(arc
							(start -0.1016 0.1778)
							(mid -0.137521 0.162921)
							(end -0.1524 0.127)
						)
						(arc
							(start -0.1524 -0.127)
							(mid -0.137521 -0.162921)
							(end -0.1016 -0.1778)
						)
						(arc
							(start 0.1016 -0.1778)
							(mid 0.137521 -0.162921)
							(end 0.1524 -0.127)
						)
					)
					(width 0)
					(fill yes)
				)
			)
		)
		(pad "2" smd custom
			(at 0 0.2794 270)
			(size 0.0762 0.0762)
			(layers "B.Cu" "B.Mask" "B.Paste")
			(net "GND")
			(options
				(clearance outline)
				(anchor circle)
			)
			(primitives
				(gr_poly
					(pts
						(arc
							(start 0.1524 0.127)
							(mid 0.137521 0.162921)
							(end 0.1016 0.1778)
						)
						(arc
							(start -0.1016 0.1778)
							(mid -0.137521 0.162921)
							(end -0.1524 0.127)
						)
						(arc
							(start -0.1524 -0.127)
							(mid -0.137521 -0.162921)
							(end -0.1016 -0.1778)
						)
						(arc
							(start 0.1016 -0.1778)
							(mid 0.137521 -0.162921)
							(end 0.1524 -0.127)
						)
					)
					(width 0)
					(fill yes)
				)
			)
		)
	)
	(footprint ""
		(layer "B.Cu")
		(at 241.0968 -54.0004 90)
		(property "Reference" "C441"
			(at 0 0 90)
			(layer "B.SilkS")
			(hide yes)
			(effects
				(font
					(size 1.27 1.27)
				)
				(justify mirror)
			)
		)
		(property "Value" "SCD1U16V1KX-1-GP"
			(at 2.8321 -1.7399 90)
			(unlocked yes)
			(layer "B.Fab")
			(hide yes)
			(effects
				(font
					(size 1.016 1.016)
					(thickness 0.1524)
				)
				(justify mirror)
			)
		)
		(property "Device Type" "C0201H13"
			(at 2.8321 -3.2639 90)
			(unlocked yes)
			(layer "B.Fab")
			(hide yes)
			(effects
				(font
					(size 1.016 1.016)
					(thickness 0.1524)
				)
				(justify mirror)
			)
		)
		(duplicate_pad_numbers_are_jumpers no)
		(fp_rect
			(start 0.2794 0.6477)
			(end -0.2794 -0.6477)
			(stroke
				(width 0)
				(type default)
			)
			(fill no)
			(layer "B.CrtYd")
		)
		(fp_rect
			(start 0.2794 0.6477)
			(end -0.2794 -0.6477)
			(stroke
				(width 0)
				(type default)
			)
			(fill no)
			(layer "B.Fab")
		)
		(pad "1" smd custom
			(at 0 -0.2794 270)
			(size 0.0762 0.0762)
			(layers "B.Cu" "B.Mask" "B.Paste")
			(net "DUT_VDD")
			(options
				(clearance outline)
				(anchor circle)
			)
			(primitives
				(gr_poly
					(pts
						(arc
							(start 0.1524 0.127)
							(mid 0.137521 0.162921)
							(end 0.1016 0.1778)
						)
						(arc
							(start -0.1016 0.1778)
							(mid -0.137521 0.162921)
							(end -0.1524 0.127)
						)
						(arc
							(start -0.1524 -0.127)
							(mid -0.137521 -0.162921)
							(end -0.1016 -0.1778)
						)
						(arc
							(start 0.1016 -0.1778)
							(mid 0.137521 -0.162921)
							(end 0.1524 -0.127)
						)
					)
					(width 0)
					(fill yes)
				)
			)
		)
		(pad "2" smd custom
			(at 0 0.2794 270)
			(size 0.0762 0.0762)
			(layers "B.Cu" "B.Mask" "B.Paste")
			(net "GND")
			(options
				(clearance outline)
				(anchor circle)
			)
			(primitives
				(gr_poly
					(pts
						(arc
							(start 0.1524 0.127)
							(mid 0.137521 0.162921)
							(end 0.1016 0.1778)
						)
						(arc
							(start -0.1016 0.1778)
							(mid -0.137521 0.162921)
							(end -0.1524 0.127)
						)
						(arc
							(start -0.1524 -0.127)
							(mid -0.137521 -0.162921)
							(end -0.1016 -0.1778)
						)
						(arc
							(start 0.1016 -0.1778)
							(mid 0.137521 -0.162921)
							(end 0.1524 -0.127)
						)
					)
					(width 0)
					(fill yes)
				)
			)
		)
	)
	(footprint ""
		(layer "B.Cu")
		(at 222.25 -20.447)
		(property "Reference" "R3706"
			(at 0 0 0)
			(layer "B.SilkS")
			(hide yes)
			(effects
				(font
					(size 1.27 1.27)
				)
				(justify mirror)
			)
		)
		(property "Value" "4K7R2F-GP"
			(at -0.064008 -3.993896 0)
			(unlocked yes)
			(layer "B.Fab")
			(hide yes)
			(effects
				(font
					(size 1.016 1.016)
					(thickness 0.1524)
				)
				(justify mirror)
			)
		)
		(property "Device Type" "R402H16"
			(at -0.064008 -5.517896 0)
			(unlocked yes)
			(layer "B.Fab")
			(hide yes)
			(effects
				(font
					(size 1.016 1.016)
					(thickness 0.1524)
				)
				(justify mirror)
			)
		)
		(duplicate_pad_numbers_are_jumpers no)
		(fp_line
			(start -0.508 -0.9398)
			(end 0.508 -0.9398)
			(stroke
				(width 0.1524)
				(type default)
			)
			(layer "B.SilkS")
		)
		(fp_line
			(start 0.508 -0.9398)
			(end 0.508 0.9398)
			(stroke
				(width 0.1524)
				(type default)
			)
			(layer "B.SilkS")
		)
		(fp_rect
			(start 0.508 0.9398)
			(end -0.508 -0.9398)
			(stroke
				(width 0)
				(type default)
			)
			(fill no)
			(layer "B.CrtYd")
		)
		(fp_rect
			(start 0.508 0.9398)
			(end -0.508 -0.9398)
			(stroke
				(width 0)
				(type default)
			)
			(fill no)
			(layer "B.Fab")
		)
		(pad "1" smd custom
			(at 0 -0.4445 180)
			(size 0.1397 0.1397)
			(layers "B.Cu" "B.Mask" "B.Paste")
			(net "HOST8_RST_N_LS")
			(options
				(clearance outline)
				(anchor circle)
			)
			(primitives
				(gr_poly
					(pts
						(arc
							(start -0.1778 0.2794)
							(mid -0.249642 0.249642)
							(end -0.2794 0.1778)
						)
						(arc
							(start -0.2794 -0.1778)
							(mid -0.249642 -0.249642)
							(end -0.1778 -0.2794)
						)
						(arc
							(start 0.1778 -0.2794)
							(mid 0.249642 -0.249642)
							(end 0.2794 -0.1778)
						)
						(arc
							(start 0.2794 0.1778)
							(mid 0.249642 0.249642)
							(end 0.1778 0.2794)
						)
					)
					(width 0)
					(fill yes)
				)
			)
		)
		(pad "2" smd custom
			(at 0 0.4445 180)
			(size 0.1397 0.1397)
			(layers "B.Cu" "B.Mask" "B.Paste")
			(net "DUT_VDDO")
			(options
				(clearance outline)
				(anchor circle)
			)
			(primitives
				(gr_poly
					(pts
						(arc
							(start -0.1778 0.2794)
							(mid -0.249642 0.249642)
							(end -0.2794 0.1778)
						)
						(arc
							(start -0.2794 -0.1778)
							(mid -0.249642 -0.249642)
							(end -0.1778 -0.2794)
						)
						(arc
							(start 0.1778 -0.2794)
							(mid 0.249642 -0.249642)
							(end 0.2794 -0.1778)
						)
						(arc
							(start 0.2794 0.1778)
							(mid 0.249642 0.249642)
							(end 0.1778 0.2794)
						)
					)
					(width 0)
					(fill yes)
				)
			)
		)
	)
)
